(kicad_pcb
	(version 20241229)
	(generator "pcbnew")
	(generator_version "9.0")
	(general
		(thickness 1.6642)
		(legacy_teardrops no)
	)
	(paper "A3")
	(title_block
		(title "PolarFire SoM")
		(date "2025-07-22")
		(rev "1.1.4")
		(company "Antmicro Ltd")
		(comment 1 "www.antmicro.com")
		(comment 9 "footprints 384-387 of 470")
	)
	(layers
		(0 "F.Cu" mixed)
		(4 "In1.Cu" power)
		(6 "In2.Cu" signal)
		(8 "In3.Cu" power)
		(10 "In4.Cu" signal)
		(12 "In5.Cu" power)
		(14 "In6.Cu" power)
		(16 "In7.Cu" signal)
		(18 "In8.Cu" power)
		(20 "In9.Cu" signal)
		(22 "In10.Cu" power)
		(24 "In11.Cu" signal)
		(26 "In12.Cu" signal)
		(2 "B.Cu" mixed)
		(9 "F.Adhes" user "F.Adhesive")
		(11 "B.Adhes" user "B.Adhesive")
		(13 "F.Paste" user)
		(15 "B.Paste" user)
		(5 "F.SilkS" user "F.Silkscreen")
		(7 "B.SilkS" user "B.Silkscreen")
		(1 "F.Mask" user)
		(3 "B.Mask" user)
		(17 "Dwgs.User" user "User.Drawings")
		(19 "Cmts.User" user "User.Comments")
		(21 "Eco1.User" user "User.Eco1")
		(23 "Eco2.User" user "User.Eco2")
		(25 "Edge.Cuts" user)
		(27 "Margin" user)
		(31 "F.CrtYd" user "F.Courtyard")
		(29 "B.CrtYd" user "B.Courtyard")
		(35 "F.Fab" user)
		(33 "B.Fab" user)
	)
	(footprint "antmicro-footprints:C_0402_1005Metric"
		(layer "B.Cu")
		(at 213.361 123.254 -90)
		(descr "Capacitor SMD 0402")
		(tags "capacitor SMD 0402")
		(property "Reference" "C254"
			(at 1.886 -0.599 90)
			(layer "B.SilkS")
			(effects
				(font
					(size 0.7 0.7)
					(thickness 0.15)
				)
				(justify left bottom mirror)
			)
		)
		(property "Value" "C_10n_0402"
			(at -1.022927 -2.155213 90)
			(layer "B.Fab")
			(hide yes)
			(effects
				(font
					(size 0.7 0.7)
					(thickness 0.15)
				)
				(justify left bottom mirror)
			)
		)
		(property "Datasheet" "https://www.murata.com/products/productdetail?partno=GRM155R71H103KA88%23"
			(at 0 0 270)
			(layer "F.Fab")
			(hide yes)
			(effects
				(font
					(size 1.27 1.27)
					(thickness 0.15)
				)
			)
		)
		(property "Description" "SMD Multilayer Ceramic Capacitor, 10000 pF, 50 V, 0402 [1005 Metric], ± 10%, X7R, GRM Series"
			(at 0 0 270)
			(layer "F.Fab")
			(hide yes)
			(effects
				(font
					(size 1.27 1.27)
					(thickness 0.15)
				)
			)
		)
		(property "Author" "Antmicro"
			(at 90.107 336.615 0)
			(layer "B.Fab")
			(hide yes)
			(effects
				(font
					(size 1 1)
					(thickness 0.15)
				)
				(justify mirror)
			)
		)
		(property "Dielectric" "X7R"
			(at 90.107 336.615 0)
			(layer "B.Fab")
			(hide yes)
			(effects
				(font
					(size 1 1)
					(thickness 0.15)
				)
				(justify mirror)
			)
		)
		(property "License" "Apache-2.0"
			(at 90.107 336.615 0)
			(layer "B.Fab")
			(hide yes)
			(effects
				(font
					(size 1 1)
					(thickness 0.15)
				)
				(justify mirror)
			)
		)
		(property "MPN" "GRM155R71H103KA88D"
			(at 90.107 336.615 0)
			(layer "B.Fab")
			(hide yes)
			(effects
				(font
					(size 1 1)
					(thickness 0.15)
				)
				(justify mirror)
			)
		)
		(property "Manufacturer" "Murata"
			(at 90.107 336.615 0)
			(layer "B.Fab")
			(hide yes)
			(effects
				(font
					(size 1 1)
					(thickness 0.15)
				)
				(justify mirror)
			)
		)
		(property "Public" ""
			(at 90.107 336.615 0)
			(layer "B.Fab")
			(hide yes)
			(effects
				(font
					(size 1 1)
					(thickness 0.15)
				)
				(justify mirror)
			)
		)
		(property "Val" "10n"
			(at 90.107 336.615 0)
			(layer "B.Fab")
			(hide yes)
			(effects
				(font
					(size 1 1)
					(thickness 0.15)
				)
				(justify mirror)
			)
		)
		(property "Voltage" "50V"
			(at 90.107 336.615 0)
			(layer "B.Fab")
			(hide yes)
			(effects
				(font
					(size 1 1)
					(thickness 0.15)
				)
				(justify mirror)
			)
		)
		(sheetname "/Ethernet/")
		(sheetfile "ethernet.kicad_sch")
		(attr smd)
		(fp_rect
			(start -0.925 0.47)
			(end 0.925 -0.47)
			(stroke
				(width 0.05)
				(type default)
			)
			(fill no)
			(layer "B.CrtYd")
		)
		(fp_line
			(start -0.494 0.25)
			(end 0.504 0.25)
			(stroke
				(width 0.15)
				(type solid)
			)
			(layer "B.Fab")
		)
		(fp_line
			(start 0.504 0.25)
			(end 0.504 -0.248)
			(stroke
				(width 0.15)
				(type solid)
			)
			(layer "B.Fab")
		)
		(fp_line
			(start -0.494 -0.248)
			(end -0.494 0.25)
			(stroke
				(width 0.15)
				(type solid)
			)
			(layer "B.Fab")
		)
		(fp_line
			(start 0.504 -0.248)
			(end -0.494 -0.248)
			(stroke
				(width 0.15)
				(type solid)
			)
			(layer "B.Fab")
		)
		(fp_text user "${REFERENCE}"
			(at -0.939 -4.599 90)
			(layer "B.Fab")
			(effects
				(font
					(size 0.7 0.7)
					(thickness 0.15)
				)
				(justify left bottom mirror)
			)
		)
		(fp_text user "License: Apache-2.0"
			(at -0.939 -5.799 90)
			(layer "B.Fab")
			(effects
				(font
					(size 0.7 0.7)
					(thickness 0.15)
				)
				(justify left bottom mirror)
			)
		)
		(fp_text user "Author: Antmicro"
			(at -0.939 -3.399 90)
			(layer "B.Fab")
			(effects
				(font
					(size 0.7 0.7)
					(thickness 0.15)
				)
				(justify left bottom mirror)
			)
		)
		(pad "1" smd roundrect
			(at -0.48 0 270)
			(size 0.59 0.64)
			(layers "B.Cu" "B.Mask" "B.Paste")
			(roundrect_rratio 0.25)
			(net 417 "GND")
			(pintype "passive")
		)
		(pad "2" smd roundrect
			(at 0.48 0 270)
			(size 0.59 0.64)
			(layers "B.Cu" "B.Mask" "B.Paste")
			(roundrect_rratio 0.25)
			(net 50 "+3V3")
			(pintype "passive")
		)
	)
	(footprint "antmicro-footprints:R_0402_1005Metric"
		(layer "B.Cu")
		(at 187.875 154.42 -90)
		(descr "Resistor SMD 0402")
		(tags "resistor SMD 0402")
		(property "Reference" "R79"
			(at 1.08 -2.575 180)
			(layer "B.SilkS")
			(effects
				(font
					(size 0.7 0.7)
					(thickness 0.15)
				)
				(justify left bottom mirror)
			)
		)
		(property "Value" "R_2k2_0402"
			(at -1.011843 -1.772047 90)
			(layer "B.Fab")
			(hide yes)
			(effects
				(font
					(size 0.7 0.7)
					(thickness 0.15)
				)
				(justify left bottom mirror)
			)
		)
		(property "Datasheet" "https://www.bourns.com/docs/product-datasheets/cr.pdf"
			(at 0 0 270)
			(layer "F.Fab")
			(hide yes)
			(effects
				(font
					(size 1.27 1.27)
					(thickness 0.15)
				)
			)
		)
		(property "Description" "SMD Chip Resistor, 2.2 kohm, ± 1%, 62.5 mW, 0402 [1005 Metric], Thick Film, General Purpose"
			(at 0 0 270)
			(layer "F.Fab")
			(hide yes)
			(effects
				(font
					(size 1.27 1.27)
					(thickness 0.15)
				)
			)
		)
		(property "Author" "Antmicro"
			(at 33.455 342.295 0)
			(layer "B.Fab")
			(hide yes)
			(effects
				(font
					(size 1 1)
					(thickness 0.15)
				)
				(justify mirror)
			)
		)
		(property "License" "Apache-2.0"
			(at 33.455 342.295 0)
			(layer "B.Fab")
			(hide yes)
			(effects
				(font
					(size 1 1)
					(thickness 0.15)
				)
				(justify mirror)
			)
		)
		(property "MPN" "CR0402-FX-2201GLF"
			(at 33.455 342.295 0)
			(layer "B.Fab")
			(hide yes)
			(effects
				(font
					(size 1 1)
					(thickness 0.15)
				)
				(justify mirror)
			)
		)
		(property "Manufacturer" "Bourns"
			(at 33.455 342.295 0)
			(layer "B.Fab")
			(hide yes)
			(effects
				(font
					(size 1 1)
					(thickness 0.15)
				)
				(justify mirror)
			)
		)
		(property "Public" ""
			(at 33.455 342.295 0)
			(layer "B.Fab")
			(hide yes)
			(effects
				(font
					(size 1 1)
					(thickness 0.15)
				)
				(justify mirror)
			)
		)
		(property "Tolerance" "1%"
			(at 33.455 342.295 0)
			(layer "B.Fab")
			(hide yes)
			(effects
				(font
					(size 1 1)
					(thickness 0.15)
				)
				(justify mirror)
			)
		)
		(property "Val" "2k2"
			(at 33.455 342.295 0)
			(layer "B.Fab")
			(hide yes)
			(effects
				(font
					(size 1 1)
					(thickness 0.15)
				)
				(justify mirror)
			)
		)
		(sheetname "/HDMI/")
		(sheetfile "hdmi.kicad_sch")
		(attr smd)
		(fp_rect
			(start -0.925 0.47)
			(end 0.925 -0.47)
			(stroke
				(width 0.05)
				(type default)
			)
			(fill no)
			(layer "B.CrtYd")
		)
		(fp_rect
			(start -0.5 0.25)
			(end 0.5 -0.25)
			(stroke
				(width 0.15)
				(type solid)
			)
			(fill no)
			(layer "B.Fab")
		)
		(fp_text user "Author: Antmicro"
			(at -0.95 -4.169 90)
			(layer "B.Fab")
			(effects
				(font
					(size 0.7 0.7)
					(thickness 0.15)
				)
				(justify left bottom mirror)
			)
		)
		(fp_text user "${REFERENCE}"
			(at -0.95 -3.168 90)
			(layer "B.Fab")
			(effects
				(font
					(size 0.7 0.7)
					(thickness 0.15)
				)
				(justify left bottom mirror)
			)
		)
		(fp_text user "License: Apache-2.0"
			(at -0.95 -5.169 90)
			(layer "B.Fab")
			(effects
				(font
					(size 0.7 0.7)
					(thickness 0.15)
				)
				(justify left bottom mirror)
			)
		)
		(pad "1" smd roundrect
			(at -0.48 0 270)
			(size 0.59 0.64)
			(layers "B.Cu" "B.Mask" "B.Paste")
			(roundrect_rratio 0.25)
			(net 218 "/Bottom Connector/HDMI0.SCL")
			(pintype "passive")
		)
		(pad "2" smd roundrect
			(at 0.48 0 270)
			(size 0.59 0.64)
			(layers "B.Cu" "B.Mask" "B.Paste")
			(roundrect_rratio 0.25)
			(net 90 "+5V")
			(pintype "passive")
		)
	)
	(footprint "antmicro-footprints:C_0402_1005Metric"
		(layer "B.Cu")
		(at 184.975 142.9875 -90)
		(descr "Capacitor SMD 0402")
		(tags "capacitor SMD 0402")
		(property "Reference" "C109"
			(at 0.7125 -3.3 180)
			(layer "B.SilkS")
			(effects
				(font
					(size 0.7 0.7)
					(thickness 0.15)
				)
				(justify left bottom mirror)
			)
		)
		(property "Value" "C_22u_0402"
			(at -1.022927 -2.155213 90)
			(layer "B.Fab")
			(hide yes)
			(effects
				(font
					(size 0.7 0.7)
					(thickness 0.15)
				)
				(justify left bottom mirror)
			)
		)
		(property "Datasheet" "https://www.murata.com/products/productdetail?partno=GRM158R60J226ME01%23"
			(at 0 0 90)
			(layer "F.Fab")
			(hide yes)
			(effects
				(font
					(size 1.27 1.27)
					(thickness 0.15)
				)
			)
		)
		(property "Description" "SMD Multilayer Ceramic Capacitor, 22 uF, 4 V, 0402 [1005 Metric], X6S"
			(at 0 0 90)
			(layer "F.Fab")
			(hide yes)
			(effects
				(font
					(size 1.27 1.27)
					(thickness 0.15)
				)
			)
		)
		(property "Author" "Antmicro"
			(at 41.9875 327.9625 0)
			(layer "B.Fab")
			(hide yes)
			(effects
				(font
					(size 1 1)
					(thickness 0.15)
				)
				(justify mirror)
			)
		)
		(property "Dielectric" ""
			(at 41.9875 327.9625 0)
			(layer "B.Fab")
			(hide yes)
			(effects
				(font
					(size 1 1)
					(thickness 0.15)
				)
				(justify mirror)
			)
		)
		(property "License" "Apache-2.0"
			(at 41.9875 327.9625 0)
			(layer "B.Fab")
			(hide yes)
			(effects
				(font
					(size 1 1)
					(thickness 0.15)
				)
				(justify mirror)
			)
		)
		(property "MPN" "GRM158R60J226ME01D"
			(at 41.9875 327.9625 0)
			(layer "B.Fab")
			(hide yes)
			(effects
				(font
					(size 1 1)
					(thickness 0.15)
				)
				(justify mirror)
			)
		)
		(property "Manufacturer" "Murata"
			(at 41.9875 327.9625 0)
			(layer "B.Fab")
			(hide yes)
			(effects
				(font
					(size 1 1)
					(thickness 0.15)
				)
				(justify mirror)
			)
		)
		(property "Public" ""
			(at 41.9875 327.9625 0)
			(layer "B.Fab")
			(hide yes)
			(effects
				(font
					(size 1 1)
					(thickness 0.15)
				)
				(justify mirror)
			)
		)
		(property "Val" "22u"
			(at 41.9875 327.9625 0)
			(layer "B.Fab")
			(hide yes)
			(effects
				(font
					(size 1 1)
					(thickness 0.15)
				)
				(justify mirror)
			)
		)
		(property "Voltage" ""
			(at 41.9875 327.9625 0)
			(layer "B.Fab")
			(hide yes)
			(effects
				(font
					(size 1 1)
					(thickness 0.15)
				)
				(justify mirror)
			)
		)
		(sheetname "/Supply/")
		(sheetfile "supply.kicad_sch")
		(attr smd)
		(fp_rect
			(start -0.925 0.47)
			(end 0.925 -0.47)
			(stroke
				(width 0.05)
				(type default)
			)
			(fill no)
			(layer "B.CrtYd")
		)
		(fp_line
			(start -0.494 0.25)
			(end 0.504 0.25)
			(stroke
				(width 0.15)
				(type solid)
			)
			(layer "B.Fab")
		)
		(fp_line
			(start 0.504 0.25)
			(end 0.504 -0.248)
			(stroke
				(width 0.15)
				(type solid)
			)
			(layer "B.Fab")
		)
		(fp_line
			(start -0.494 -0.248)
			(end -0.494 0.25)
			(stroke
				(width 0.15)
				(type solid)
			)
			(layer "B.Fab")
		)
		(fp_line
			(start 0.504 -0.248)
			(end -0.494 -0.248)
			(stroke
				(width 0.15)
				(type solid)
			)
			(layer "B.Fab")
		)
		(fp_text user "${REFERENCE}"
			(at -0.939 -4.599 90)
			(layer "B.Fab")
			(effects
				(font
					(size 0.7 0.7)
					(thickness 0.15)
				)
				(justify left bottom mirror)
			)
		)
		(fp_text user "License: Apache-2.0"
			(at -0.939 -5.799 90)
			(layer "B.Fab")
			(effects
				(font
					(size 0.7 0.7)
					(thickness 0.15)
				)
				(justify left bottom mirror)
			)
		)
		(fp_text user "Author: Antmicro"
			(at -0.939 -3.399 90)
			(layer "B.Fab")
			(effects
				(font
					(size 0.7 0.7)
					(thickness 0.15)
				)
				(justify left bottom mirror)
			)
		)
		(pad "1" smd roundrect
			(at -0.48 0 270)
			(size 0.59 0.64)
			(layers "B.Cu" "B.Mask" "B.Paste")
			(roundrect_rratio 0.25)
			(net 417 "GND")
			(pintype "passive")
		)
		(pad "2" smd roundrect
			(at 0.48 0 270)
			(size 0.59 0.64)
			(layers "B.Cu" "B.Mask" "B.Paste")
			(roundrect_rratio 0.25)
			(net 409 "/Supply/SENSE4_P")
			(pintype "passive")
		)
	)
	(footprint "antmicro-footprints:R_0402_1005Metric"
		(layer "B.Cu")
		(at 187.875 152.47 90)
		(descr "Resistor SMD 0402")
		(tags "resistor SMD 0402")
		(property "Reference" "R73"
			(at 0.77 2.05 270)
			(layer "B.SilkS")
			(effects
				(font
					(size 0.7 0.7)
					(thickness 0.15)
				)
				(justify left bottom mirror)
			)
		)
		(property "Value" "R_2k2_0402"
			(at -1.011843 -1.772047 270)
			(layer "B.Fab")
			(hide yes)
			(effects
				(font
					(size 0.7 0.7)
					(thickness 0.15)
				)
				(justify left bottom mirror)
			)
		)
		(property "Datasheet" "https://www.bourns.com/docs/product-datasheets/cr.pdf"
			(at 0 0 90)
			(layer "F.Fab")
			(hide yes)
			(effects
				(font
					(size 1.27 1.27)
					(thickness 0.15)
				)
			)
		)
		(property "Description" "SMD Chip Resistor, 2.2 kohm, ± 1%, 62.5 mW, 0402 [1005 Metric], Thick Film, General Purpose"
			(at 0 0 90)
			(layer "F.Fab")
			(hide yes)
			(effects
				(font
					(size 1.27 1.27)
					(thickness 0.15)
				)
			)
		)
		(property "Author" "Antmicro"
			(at 340.345 -35.405 0)
			(layer "B.Fab")
			(hide yes)
			(effects
				(font
					(size 1 1)
					(thickness 0.15)
				)
				(justify mirror)
			)
		)
		(property "License" "Apache-2.0"
			(at 340.345 -35.405 0)
			(layer "B.Fab")
			(hide yes)
			(effects
				(font
					(size 1 1)
					(thickness 0.15)
				)
				(justify mirror)
			)
		)
		(property "MPN" "CR0402-FX-2201GLF"
			(at 340.345 -35.405 0)
			(layer "B.Fab")
			(hide yes)
			(effects
				(font
					(size 1 1)
					(thickness 0.15)
				)
				(justify mirror)
			)
		)
		(property "Manufacturer" "Bourns"
			(at 340.345 -35.405 0)
			(layer "B.Fab")
			(hide yes)
			(effects
				(font
					(size 1 1)
					(thickness 0.15)
				)
				(justify mirror)
			)
		)
		(property "Public" ""
			(at 340.345 -35.405 0)
			(layer "B.Fab")
			(hide yes)
			(effects
				(font
					(size 1 1)
					(thickness 0.15)
				)
				(justify mirror)
			)
		)
		(property "Tolerance" "1%"
			(at 340.345 -35.405 0)
			(layer "B.Fab")
			(hide yes)
			(effects
				(font
					(size 1 1)
					(thickness 0.15)
				)
				(justify mirror)
			)
		)
		(property "Val" "2k2"
			(at 340.345 -35.405 0)
			(layer "B.Fab")
			(hide yes)
			(effects
				(font
					(size 1 1)
					(thickness 0.15)
				)
				(justify mirror)
			)
		)
		(sheetname "/HDMI/")
		(sheetfile "hdmi.kicad_sch")
		(attr smd)
		(fp_rect
			(start -0.925 0.47)
			(end 0.925 -0.47)
			(stroke
				(width 0.05)
				(type default)
			)
			(fill no)
			(layer "B.CrtYd")
		)
		(fp_rect
			(start -0.5 0.25)
			(end 0.5 -0.25)
			(stroke
				(width 0.15)
				(type solid)
			)
			(fill no)
			(layer "B.Fab")
		)
		(fp_text user "${REFERENCE}"
			(at -0.95 -3.168 270)
			(layer "B.Fab")
			(effects
				(font
					(size 0.7 0.7)
					(thickness 0.15)
				)
				(justify left bottom mirror)
			)
		)
		(fp_text user "License: Apache-2.0"
			(at -0.95 -5.169 270)
			(layer "B.Fab")
			(effects
				(font
					(size 0.7 0.7)
					(thickness 0.15)
				)
				(justify left bottom mirror)
			)
		)
		(fp_text user "Author: Antmicro"
			(at -0.95 -4.169 270)
			(layer "B.Fab")
			(effects
				(font
					(size 0.7 0.7)
					(thickness 0.15)
				)
				(justify left bottom mirror)
			)
		)
		(pad "1" smd roundrect
			(at -0.48 0 90)
			(size 0.59 0.64)
			(layers "B.Cu" "B.Mask" "B.Paste")
			(roundrect_rratio 0.25)
			(net 206 "/Bottom Connector/HDMI0.SDA")
			(pintype "passive")
		)
		(pad "2" smd roundrect
			(at 0.48 0 90)
			(size 0.59 0.64)
			(layers "B.Cu" "B.Mask" "B.Paste")
			(roundrect_rratio 0.25)
			(net 90 "+5V")
			(pintype "passive")
		)
	)
)
